FILE_TYPE = CONNECTIVITY;
{Allegro Design Entry HDL 17.4-2019 S026 (4007227) 1/17/2022}
"PAGE_NUMBER" = 133;
0"NC";
END.
